(kicad_pcb
	(version 20260206)
	(generator "pcbnew")
	(generator_version "10.0")
	(general
		(thickness 1.6)
		(legacy_teardrops no)
	)
	(paper "A4")
	(title_block
		(title "panther-plus-userver — 13130-1b_20150205.brd")
		(comment 1 "Honey Badger (Wiwynn) / footprint 406 of 1509 (DIMM2), pads 79-85 of 210")
	)
	(layers
		(0 "F.Cu" signal "TOP")
		(4 "In1.Cu" signal "L2")
		(6 "In2.Cu" signal "L3")
		(8 "In3.Cu" signal "L4")
		(10 "In4.Cu" signal "L5")
		(12 "In5.Cu" signal "L6")
		(14 "In6.Cu" signal "L7")
		(16 "In7.Cu" signal "L8")
		(18 "In8.Cu" signal "L9")
		(20 "In9.Cu" signal "L10")
		(22 "In10.Cu" signal "L11")
		(2 "B.Cu" signal "BOTTOM")
		(9 "F.Adhes" user "F.Adhesive")
		(11 "B.Adhes" user "B.Adhesive")
		(13 "F.Paste" user "Package Geometry/Pastemask Top")
		(15 "B.Paste" user "Package Geometry/Pastemask Bottom")
		(5 "F.SilkS" user "Ref Des/Silkscreen Top")
		(7 "B.SilkS" user "Ref Des/Silkscreen Bottom")
		(1 "F.Mask" user "Board Geometry/Soldermask Top")
		(3 "B.Mask" user "Board Geometry/Soldermask Bottom")
		(17 "Dwgs.User" user "User.Drawings")
		(19 "Cmts.User" user "User.Comments")
		(21 "Eco1.User" user "User.Eco1")
		(23 "Eco2.User" user "User.Eco2")
		(25 "Edge.Cuts" user "Board Geometry/Outline")
		(27 "Margin" user)
		(31 "F.CrtYd" user "Package Geometry/Place Bound Top")
		(29 "B.CrtYd" user "Package Geometry/Place Bound Bottom")
		(35 "F.Fab" user "Ref Des/Assembly Top")
		(33 "B.Fab" user "Ref Des/Assembly Bottom")
	)
	(footprint ""
		(layer "F.Cu")
		(at 158.500064 -66.699892 180)
		(property "Reference" "DIMM2"
			(at 0 0 180)
			(layer "F.SilkS")
			(hide yes)
			(effects
				(font
					(size 1.27 1.27)
				)
			)
		)
		(property "Value" "DDR3-204P-174-COLAY-1-GP"
			(at -40.682164 -17.468088 180)
			(unlocked yes)
			(layer "F.Fab")
			(hide yes)
			(effects
				(font
					(size 1.016 1.016)
					(thickness 0.1524)
				)
			)
		)
		(property "Device Type" "AS0A626-H8SN-7H-COLAY-1"
			(at -40.682164 -18.992088 180)
			(unlocked yes)
			(layer "F.Fab")
			(hide yes)
			(effects
				(font
					(size 1.016 1.016)
					(thickness 0.1524)
				)
			)
		)
		(duplicate_pad_numbers_are_jumpers no)
		(pad "77" smd custom
			(at -6.450076 4.106672 180)
			(size 0.1143 0.1143)
			(layers "F.Cu" "F.Mask" "F.Paste")
			(net "M_A_DQS_DP8")
			(options
				(clearance outline)
				(anchor circle)
			)
			(primitives
				(gr_poly
					(pts
						(xy 0 0.9017) (xy -0.03175 0.89916) (xy -0.0635 0.889) (xy -0.09144 0.87376) (xy -0.11684 0.85344)
						(xy -0.13716 0.82804) (xy -0.1524 0.8001) (xy -0.16256 0.76835) (xy -0.1651 0.7366) (xy -0.1651 -0.13462)
						(xy -0.17272 -0.14224) (xy -0.19812 -0.1778) (xy -0.2032 -0.18796) (xy -0.20701 -0.19685) (xy -0.21209 -0.20701)
						(xy -0.2159 -0.21717) (xy -0.21844 -0.22733) (xy -0.22225 -0.23876) (xy -0.22352 -0.24892) (xy -0.22606 -0.25908)
						(xy -0.22733 -0.27051) (xy -0.22733 -0.28067) (xy -0.2286 -0.2921) (xy -0.22733 -0.30353) (xy -0.22733 -0.31369)
						(xy -0.22606 -0.32512) (xy -0.22352 -0.33528) (xy -0.22225 -0.34544) (xy -0.21844 -0.35687) (xy -0.2159 -0.36703)
						(xy -0.21209 -0.37719) (xy -0.20701 -0.38735) (xy -0.2032 -0.39624) (xy -0.19812 -0.4064) (xy -0.17272 -0.44196)
						(xy -0.1651 -0.44958) (xy -0.1651 -0.7366) (xy -0.16256 -0.76835) (xy -0.1524 -0.8001) (xy -0.13716 -0.82804)
						(xy -0.11684 -0.85344) (xy -0.09144 -0.87376) (xy -0.0635 -0.889) (xy -0.03175 -0.89916) (xy 0 -0.9017)
						(xy 0.03175 -0.89916) (xy 0.0635 -0.889) (xy 0.09144 -0.87376) (xy 0.11684 -0.85344) (xy 0.13716 -0.82804)
						(xy 0.1524 -0.8001) (xy 0.16256 -0.76835) (xy 0.1651 -0.7366) (xy 0.1651 -0.44958) (xy 0.17272 -0.44196)
						(xy 0.19812 -0.4064) (xy 0.2032 -0.39624) (xy 0.20701 -0.38735) (xy 0.21209 -0.37719) (xy 0.2159 -0.36703)
						(xy 0.21844 -0.35687) (xy 0.22225 -0.34544) (xy 0.22352 -0.33528) (xy 0.22606 -0.32512) (xy 0.22733 -0.31369)
						(xy 0.22733 -0.30353) (xy 0.2286 -0.2921) (xy 0.22733 -0.28067) (xy 0.22733 -0.27051) (xy 0.22606 -0.25908)
						(xy 0.22352 -0.24892) (xy 0.22225 -0.23876) (xy 0.21844 -0.22733) (xy 0.2159 -0.21717) (xy 0.21209 -0.20701)
						(xy 0.20701 -0.19685) (xy 0.2032 -0.18796) (xy 0.19812 -0.1778) (xy 0.17272 -0.14224) (xy 0.1651 -0.13462)
						(xy 0.1651 0.7366) (xy 0.16256 0.76835) (xy 0.1524 0.8001) (xy 0.13716 0.82804) (xy 0.11684 0.85344)
						(xy 0.09144 0.87376) (xy 0.0635 0.889) (xy 0.03175 0.89916)
					)
					(width 0)
					(fill yes)
				)
			)
		)
		(pad "78" smd custom
			(at -6.150102 -4.106672 180)
			(size 0.1143 0.1143)
			(layers "F.Cu" "F.Mask" "F.Paste")
			(net "GND")
			(options
				(clearance outline)
				(anchor circle)
			)
			(primitives
				(gr_poly
					(pts
						(xy 0 0.9017) (xy -0.03175 0.89916) (xy -0.0635 0.889) (xy -0.09144 0.87376) (xy -0.11684 0.85344)
						(xy -0.13716 0.82804) (xy -0.1524 0.8001) (xy -0.16256 0.76835) (xy -0.1651 0.7366) (xy -0.1651 0.44958)
						(xy -0.17272 0.44196) (xy -0.19812 0.4064) (xy -0.2032 0.39624) (xy -0.20701 0.38735) (xy -0.21209 0.37719)
						(xy -0.2159 0.36703) (xy -0.21844 0.35687) (xy -0.22225 0.34544) (xy -0.22352 0.33528) (xy -0.22606 0.32512)
						(xy -0.22733 0.31369) (xy -0.22733 0.30353) (xy -0.2286 0.2921) (xy -0.22733 0.28067) (xy -0.22733 0.27051)
						(xy -0.22606 0.25908) (xy -0.22352 0.24892) (xy -0.22225 0.23876) (xy -0.21844 0.22733) (xy -0.2159 0.21717)
						(xy -0.21209 0.20701) (xy -0.20701 0.19685) (xy -0.2032 0.18796) (xy -0.19812 0.1778) (xy -0.17272 0.14224)
						(xy -0.1651 0.13462) (xy -0.1651 -0.7366) (xy -0.16256 -0.76835) (xy -0.1524 -0.8001) (xy -0.13716 -0.82804)
						(xy -0.11684 -0.85344) (xy -0.09144 -0.87376) (xy -0.0635 -0.889) (xy -0.03175 -0.89916) (xy 0 -0.9017)
						(xy 0.03175 -0.89916) (xy 0.0635 -0.889) (xy 0.09144 -0.87376) (xy 0.11684 -0.85344) (xy 0.13716 -0.82804)
						(xy 0.1524 -0.8001) (xy 0.16256 -0.76835) (xy 0.1651 -0.7366) (xy 0.1651 0.13462) (xy 0.17272 0.14224)
						(xy 0.19812 0.1778) (xy 0.2032 0.18796) (xy 0.20701 0.19685) (xy 0.21209 0.20701) (xy 0.2159 0.21717)
						(xy 0.21844 0.22733) (xy 0.22225 0.23876) (xy 0.22352 0.24892) (xy 0.22606 0.25908) (xy 0.22733 0.27051)
						(xy 0.22733 0.28067) (xy 0.2286 0.2921) (xy 0.22733 0.30353) (xy 0.22733 0.31369) (xy 0.22606 0.32512)
						(xy 0.22352 0.33528) (xy 0.22225 0.34544) (xy 0.21844 0.35687) (xy 0.2159 0.36703) (xy 0.21209 0.37719)
						(xy 0.20701 0.38735) (xy 0.2032 0.39624) (xy 0.19812 0.4064) (xy 0.17272 0.44196) (xy 0.1651 0.44958)
						(xy 0.1651 0.7366) (xy 0.16256 0.76835) (xy 0.1524 0.8001) (xy 0.13716 0.82804) (xy 0.11684 0.85344)
						(xy 0.09144 0.87376) (xy 0.0635 0.889) (xy 0.03175 0.89916)
					)
					(width 0)
					(fill yes)
				)
			)
		)
		(pad "79" smd custom
			(at -5.849874 4.106672 180)
			(size 0.1143 0.1143)
			(layers "F.Cu" "F.Mask" "F.Paste")
			(net "GND")
			(options
				(clearance outline)
				(anchor circle)
			)
			(primitives
				(gr_poly
					(pts
						(xy 0 0.9017) (xy -0.03175 0.89916) (xy -0.0635 0.889) (xy -0.09144 0.87376) (xy -0.11684 0.85344)
						(xy -0.13716 0.82804) (xy -0.1524 0.8001) (xy -0.16256 0.76835) (xy -0.1651 0.7366) (xy -0.1651 0.11938)
						(xy -0.17272 0.11176) (xy -0.19812 0.0762) (xy -0.2032 0.06604) (xy -0.20701 0.05715) (xy -0.21209 0.04699)
						(xy -0.2159 0.03683) (xy -0.21844 0.02667) (xy -0.22225 0.01524) (xy -0.22352 0.00508) (xy -0.22606 -0.00508)
						(xy -0.22733 -0.01651) (xy -0.22733 -0.02667) (xy -0.2286 -0.0381) (xy -0.22733 -0.04953) (xy -0.22733 -0.05969)
						(xy -0.22606 -0.07112) (xy -0.22352 -0.08128) (xy -0.22225 -0.09144) (xy -0.21844 -0.10287) (xy -0.2159 -0.11303)
						(xy -0.21209 -0.12319) (xy -0.20701 -0.13335) (xy -0.2032 -0.14224) (xy -0.19812 -0.1524) (xy -0.17272 -0.18796)
						(xy -0.1651 -0.19558) (xy -0.1651 -0.7366) (xy -0.16256 -0.76835) (xy -0.1524 -0.8001) (xy -0.13716 -0.82804)
						(xy -0.11684 -0.85344) (xy -0.09144 -0.87376) (xy -0.0635 -0.889) (xy -0.03175 -0.89916) (xy 0 -0.9017)
						(xy 0.03175 -0.89916) (xy 0.0635 -0.889) (xy 0.09144 -0.87376) (xy 0.11684 -0.85344) (xy 0.13716 -0.82804)
						(xy 0.1524 -0.8001) (xy 0.16256 -0.76835) (xy 0.1651 -0.7366) (xy 0.1651 -0.19685) (xy 0.17272 -0.18923)
						(xy 0.17907 -0.18034) (xy 0.18669 -0.17145) (xy 0.19177 -0.16256) (xy 0.19812 -0.15367) (xy 0.20828 -0.13335)
						(xy 0.21971 -0.10287) (xy 0.22225 -0.09271) (xy 0.22479 -0.08128) (xy 0.22606 -0.07112) (xy 0.2286 -0.05969)
						(xy 0.2286 -0.01651) (xy 0.22606 -0.00508) (xy 0.22479 0.00508) (xy 0.22225 0.01651) (xy 0.21971 0.02667)
						(xy 0.20828 0.05715) (xy 0.19812 0.07747) (xy 0.19177 0.08636) (xy 0.18669 0.09525) (xy 0.17907 0.10414)
						(xy 0.17272 0.11303) (xy 0.1651 0.12065) (xy 0.1651 0.7366) (xy 0.16256 0.76835) (xy 0.1524 0.8001)
						(xy 0.13716 0.82804) (xy 0.11684 0.85344) (xy 0.09144 0.87376) (xy 0.0635 0.889) (xy 0.03175 0.89916)
					)
					(width 0)
					(fill yes)
				)
			)
		)
		(pad "80" smd custom
			(at -5.5499 -4.106672 180)
			(size 0.1143 0.1143)
			(layers "F.Cu" "F.Mask" "F.Paste")
			(net "M_A_ECC2")
			(options
				(clearance outline)
				(anchor circle)
			)
			(primitives
				(gr_poly
					(pts
						(xy 0 0.9017) (xy -0.03175 0.89916) (xy -0.0635 0.889) (xy -0.09144 0.87376) (xy -0.11684 0.85344)
						(xy -0.13716 0.82804) (xy -0.1524 0.8001) (xy -0.16256 0.76835) (xy -0.1651 0.7366) (xy -0.1651 0.19685)
						(xy -0.17272 0.18923) (xy -0.17907 0.18034) (xy -0.18669 0.17145) (xy -0.19177 0.16256) (xy -0.19812 0.15367)
						(xy -0.20828 0.13335) (xy -0.21971 0.10287) (xy -0.22225 0.09271) (xy -0.22479 0.08128) (xy -0.22606 0.07112)
						(xy -0.2286 0.05969) (xy -0.2286 0.01651) (xy -0.22606 0.00508) (xy -0.22479 -0.00508) (xy -0.22225 -0.01651)
						(xy -0.21971 -0.02667) (xy -0.20828 -0.05715) (xy -0.19812 -0.07747) (xy -0.19177 -0.08636) (xy -0.18669 -0.09525)
						(xy -0.17907 -0.10414) (xy -0.17272 -0.11303) (xy -0.1651 -0.12065) (xy -0.1651 -0.7366) (xy -0.16256 -0.76835)
						(xy -0.1524 -0.8001) (xy -0.13716 -0.82804) (xy -0.11684 -0.85344) (xy -0.09144 -0.87376) (xy -0.0635 -0.889)
						(xy -0.03175 -0.89916) (xy 0 -0.9017) (xy 0.03175 -0.89916) (xy 0.0635 -0.889) (xy 0.09144 -0.87376)
						(xy 0.11684 -0.85344) (xy 0.13716 -0.82804) (xy 0.1524 -0.8001) (xy 0.16256 -0.76835) (xy 0.1651 -0.7366)
						(xy 0.1651 -0.11938) (xy 0.17272 -0.11176) (xy 0.19812 -0.0762) (xy 0.2032 -0.06604) (xy 0.20701 -0.05715)
						(xy 0.21209 -0.04699) (xy 0.2159 -0.03683) (xy 0.21844 -0.02667) (xy 0.22225 -0.01524) (xy 0.22352 -0.00508)
						(xy 0.22606 0.00508) (xy 0.22733 0.01651) (xy 0.22733 0.02667) (xy 0.2286 0.0381) (xy 0.22733 0.04953)
						(xy 0.22733 0.05969) (xy 0.22606 0.07112) (xy 0.22352 0.08128) (xy 0.22225 0.09144) (xy 0.21844 0.10287)
						(xy 0.2159 0.11303) (xy 0.21209 0.12319) (xy 0.20701 0.13335) (xy 0.2032 0.14224) (xy 0.19812 0.1524)
						(xy 0.17272 0.18796) (xy 0.1651 0.19558) (xy 0.1651 0.7366) (xy 0.16256 0.76835) (xy 0.1524 0.8001)
						(xy 0.13716 0.82804) (xy 0.11684 0.85344) (xy 0.09144 0.87376) (xy 0.0635 0.889) (xy 0.03175 0.89916)
					)
					(width 0)
					(fill yes)
				)
			)
		)
		(pad "81" smd custom
			(at -5.249926 4.106672 180)
			(size 0.1143 0.1143)
			(layers "F.Cu" "F.Mask" "F.Paste")
			(net "M_A_ECC6")
			(options
				(clearance outline)
				(anchor circle)
			)
			(primitives
				(gr_poly
					(pts
						(xy 0 0.9017) (xy -0.03175 0.89916) (xy -0.0635 0.889) (xy -0.09144 0.87376) (xy -0.11684 0.85344)
						(xy -0.13716 0.82804) (xy -0.1524 0.8001) (xy -0.16256 0.76835) (xy -0.1651 0.7366) (xy -0.1651 -0.13462)
						(xy -0.17272 -0.14224) (xy -0.19812 -0.1778) (xy -0.2032 -0.18796) (xy -0.20701 -0.19685) (xy -0.21209 -0.20701)
						(xy -0.2159 -0.21717) (xy -0.21844 -0.22733) (xy -0.22225 -0.23876) (xy -0.22352 -0.24892) (xy -0.22606 -0.25908)
						(xy -0.22733 -0.27051) (xy -0.22733 -0.28067) (xy -0.2286 -0.2921) (xy -0.22733 -0.30353) (xy -0.22733 -0.31369)
						(xy -0.22606 -0.32512) (xy -0.22352 -0.33528) (xy -0.22225 -0.34544) (xy -0.21844 -0.35687) (xy -0.2159 -0.36703)
						(xy -0.21209 -0.37719) (xy -0.20701 -0.38735) (xy -0.2032 -0.39624) (xy -0.19812 -0.4064) (xy -0.17272 -0.44196)
						(xy -0.1651 -0.44958) (xy -0.1651 -0.7366) (xy -0.16256 -0.76835) (xy -0.1524 -0.8001) (xy -0.13716 -0.82804)
						(xy -0.11684 -0.85344) (xy -0.09144 -0.87376) (xy -0.0635 -0.889) (xy -0.03175 -0.89916) (xy 0 -0.9017)
						(xy 0.03175 -0.89916) (xy 0.0635 -0.889) (xy 0.09144 -0.87376) (xy 0.11684 -0.85344) (xy 0.13716 -0.82804)
						(xy 0.1524 -0.8001) (xy 0.16256 -0.76835) (xy 0.1651 -0.7366) (xy 0.1651 -0.44958) (xy 0.17272 -0.44196)
						(xy 0.19812 -0.4064) (xy 0.2032 -0.39624) (xy 0.20701 -0.38735) (xy 0.21209 -0.37719) (xy 0.2159 -0.36703)
						(xy 0.21844 -0.35687) (xy 0.22225 -0.34544) (xy 0.22352 -0.33528) (xy 0.22606 -0.32512) (xy 0.22733 -0.31369)
						(xy 0.22733 -0.30353) (xy 0.2286 -0.2921) (xy 0.22733 -0.28067) (xy 0.22733 -0.27051) (xy 0.22606 -0.25908)
						(xy 0.22352 -0.24892) (xy 0.22225 -0.23876) (xy 0.21844 -0.22733) (xy 0.2159 -0.21717) (xy 0.21209 -0.20701)
						(xy 0.20701 -0.19685) (xy 0.2032 -0.18796) (xy 0.19812 -0.1778) (xy 0.17272 -0.14224) (xy 0.1651 -0.13462)
						(xy 0.1651 0.7366) (xy 0.16256 0.76835) (xy 0.1524 0.8001) (xy 0.13716 0.82804) (xy 0.11684 0.85344)
						(xy 0.09144 0.87376) (xy 0.0635 0.889) (xy 0.03175 0.89916)
					)
					(width 0)
					(fill yes)
				)
			)
		)
		(pad "82" smd custom
			(at -4.949952 -4.106672 180)
			(size 0.1143 0.1143)
			(layers "F.Cu" "F.Mask" "F.Paste")
			(net "M_A_ECC3")
			(options
				(clearance outline)
				(anchor circle)
			)
			(primitives
				(gr_poly
					(pts
						(xy 0 0.9017) (xy -0.03175 0.89916) (xy -0.0635 0.889) (xy -0.09144 0.87376) (xy -0.11684 0.85344)
						(xy -0.13716 0.82804) (xy -0.1524 0.8001) (xy -0.16256 0.76835) (xy -0.1651 0.7366) (xy -0.1651 0.44958)
						(xy -0.17272 0.44196) (xy -0.19812 0.4064) (xy -0.2032 0.39624) (xy -0.20701 0.38735) (xy -0.21209 0.37719)
						(xy -0.2159 0.36703) (xy -0.21844 0.35687) (xy -0.22225 0.34544) (xy -0.22352 0.33528) (xy -0.22606 0.32512)
						(xy -0.22733 0.31369) (xy -0.22733 0.30353) (xy -0.2286 0.2921) (xy -0.22733 0.28067) (xy -0.22733 0.27051)
						(xy -0.22606 0.25908) (xy -0.22352 0.24892) (xy -0.22225 0.23876) (xy -0.21844 0.22733) (xy -0.2159 0.21717)
						(xy -0.21209 0.20701) (xy -0.20701 0.19685) (xy -0.2032 0.18796) (xy -0.19812 0.1778) (xy -0.17272 0.14224)
						(xy -0.1651 0.13462) (xy -0.1651 -0.7366) (xy -0.16256 -0.76835) (xy -0.1524 -0.8001) (xy -0.13716 -0.82804)
						(xy -0.11684 -0.85344) (xy -0.09144 -0.87376) (xy -0.0635 -0.889) (xy -0.03175 -0.89916) (xy 0 -0.9017)
						(xy 0.03175 -0.89916) (xy 0.0635 -0.889) (xy 0.09144 -0.87376) (xy 0.11684 -0.85344) (xy 0.13716 -0.82804)
						(xy 0.1524 -0.8001) (xy 0.16256 -0.76835) (xy 0.1651 -0.7366) (xy 0.1651 0.13462) (xy 0.17272 0.14224)
						(xy 0.19812 0.1778) (xy 0.2032 0.18796) (xy 0.20701 0.19685) (xy 0.21209 0.20701) (xy 0.2159 0.21717)
						(xy 0.21844 0.22733) (xy 0.22225 0.23876) (xy 0.22352 0.24892) (xy 0.22606 0.25908) (xy 0.22733 0.27051)
						(xy 0.22733 0.28067) (xy 0.2286 0.2921) (xy 0.22733 0.30353) (xy 0.22733 0.31369) (xy 0.22606 0.32512)
						(xy 0.22352 0.33528) (xy 0.22225 0.34544) (xy 0.21844 0.35687) (xy 0.2159 0.36703) (xy 0.21209 0.37719)
						(xy 0.20701 0.38735) (xy 0.2032 0.39624) (xy 0.19812 0.4064) (xy 0.17272 0.44196) (xy 0.1651 0.44958)
						(xy 0.1651 0.7366) (xy 0.16256 0.76835) (xy 0.1524 0.8001) (xy 0.13716 0.82804) (xy 0.11684 0.85344)
						(xy 0.09144 0.87376) (xy 0.0635 0.889) (xy 0.03175 0.89916)
					)
					(width 0)
					(fill yes)
				)
			)
		)
		(pad "83" smd custom
			(at -4.649978 4.106672 180)
			(size 0.1143 0.1143)
			(layers "F.Cu" "F.Mask" "F.Paste")
			(net "M_A_ECC7")
			(options
				(clearance outline)
				(anchor circle)
			)
			(primitives
				(gr_poly
					(pts
						(xy 0 0.9017) (xy -0.03175 0.89916) (xy -0.0635 0.889) (xy -0.09144 0.87376) (xy -0.11684 0.85344)
						(xy -0.13716 0.82804) (xy -0.1524 0.8001) (xy -0.16256 0.76835) (xy -0.1651 0.7366) (xy -0.1651 0.11938)
						(xy -0.17272 0.11176) (xy -0.19812 0.0762) (xy -0.2032 0.06604) (xy -0.20701 0.05715) (xy -0.21209 0.04699)
						(xy -0.2159 0.03683) (xy -0.21844 0.02667) (xy -0.22225 0.01524) (xy -0.22352 0.00508) (xy -0.22606 -0.00508)
						(xy -0.22733 -0.01651) (xy -0.22733 -0.02667) (xy -0.2286 -0.0381) (xy -0.22733 -0.04953) (xy -0.22733 -0.05969)
						(xy -0.22606 -0.07112) (xy -0.22352 -0.08128) (xy -0.22225 -0.09144) (xy -0.21844 -0.10287) (xy -0.2159 -0.11303)
						(xy -0.21209 -0.12319) (xy -0.20701 -0.13335) (xy -0.2032 -0.14224) (xy -0.19812 -0.1524) (xy -0.17272 -0.18796)
						(xy -0.1651 -0.19558) (xy -0.1651 -0.7366) (xy -0.16256 -0.76835) (xy -0.1524 -0.8001) (xy -0.13716 -0.82804)
						(xy -0.11684 -0.85344) (xy -0.09144 -0.87376) (xy -0.0635 -0.889) (xy -0.03175 -0.89916) (xy 0 -0.9017)
						(xy 0.03175 -0.89916) (xy 0.0635 -0.889) (xy 0.09144 -0.87376) (xy 0.11684 -0.85344) (xy 0.13716 -0.82804)
						(xy 0.1524 -0.8001) (xy 0.16256 -0.76835) (xy 0.1651 -0.7366) (xy 0.1651 -0.19685) (xy 0.17272 -0.18923)
						(xy 0.17907 -0.18034) (xy 0.18669 -0.17145) (xy 0.19177 -0.16256) (xy 0.19812 -0.15367) (xy 0.20828 -0.13335)
						(xy 0.21971 -0.10287) (xy 0.22225 -0.09271) (xy 0.22479 -0.08128) (xy 0.22606 -0.07112) (xy 0.2286 -0.05969)
						(xy 0.2286 -0.01651) (xy 0.22606 -0.00508) (xy 0.22479 0.00508) (xy 0.22225 0.01651) (xy 0.21971 0.02667)
						(xy 0.20828 0.05715) (xy 0.19812 0.07747) (xy 0.19177 0.08636) (xy 0.18669 0.09525) (xy 0.17907 0.10414)
						(xy 0.17272 0.11303) (xy 0.1651 0.12065) (xy 0.1651 0.7366) (xy 0.16256 0.76835) (xy 0.1524 0.8001)
						(xy 0.13716 0.82804) (xy 0.11684 0.85344) (xy 0.09144 0.87376) (xy 0.0635 0.889) (xy 0.03175 0.89916)
					)
					(width 0)
					(fill yes)
				)
			)
		)
	)
)
